# T6G (Grand Teton) — schematic netlist excerpt (pin names and nets, part order shuffled) for the footprints in the layout excerpt that follows; sources: Cadence DE-HDL packaged netlist, KiCad conversion of 04192023_DAF0TMB3IC0_F0TG_MB_C_brd_V02_OCP.brd

C6  Q_CAP  0.1UF 25V 10% EMPTY  pkg 0402  page 124 : A = HGX_DETECT_N_ISO ; B = GND
C6059  Q_CAP  0.01UF 50V 10% X7R  pkg C0402  page 177 : A = P1V2_AUX ; B = GND
C776  Q_CAP  0.1UF 10V 10% X7S  pkg C0201  page 301 : A = P1V8_CPU0_RT2_1A ; B = GND

(kicad_pcb
	(version 20260206)
	(generator "pcbnew")
	(generator_version "10.0")
	(general
		(thickness 1.6)
		(legacy_teardrops no)
	)
	(paper "A4")
	(title_block
		(title "04192023_DAF0TMB3IC0_F0TG_MB_C_brd_V02_OCP.brd")
		(comment 1 "Grand Teton / footprints 5076-5078 of 8354")
	)
	(layers
		(0 "F.Cu" signal "TOP")
		(4 "In1.Cu" signal "GND")
		(6 "In2.Cu" signal "IN1")
		(8 "In3.Cu" signal "GND1")
		(10 "In4.Cu" signal "IN2")
		(12 "In5.Cu" signal "GND2")
		(14 "In6.Cu" signal "IN3")
		(16 "In7.Cu" signal "GND3")
		(18 "In8.Cu" signal "VCC")
		(20 "In9.Cu" signal "VCC1")
		(22 "In10.Cu" signal "GND4")
		(24 "In11.Cu" signal "IN4")
		(26 "In12.Cu" signal "GND5")
		(28 "In13.Cu" signal "IN5")
		(30 "In14.Cu" signal "GND6")
		(32 "In15.Cu" signal "IN6")
		(34 "In16.Cu" signal "GND7")
		(2 "B.Cu" signal "BOTTOM")
		(9 "F.Adhes" user "F.Adhesive")
		(11 "B.Adhes" user "B.Adhesive")
		(13 "F.Paste" user "Package Geometry/Pastemask Top")
		(15 "B.Paste" user "Package Geometry/Pastemask Bottom")
		(5 "F.SilkS" user "Ref Des/Silkscreen Top")
		(7 "B.SilkS" user "Ref Des/Silkscreen Bottom")
		(1 "F.Mask" user "Board Geometry/Soldermask Top")
		(3 "B.Mask" user "Board Geometry/Soldermask Bottom")
		(17 "Dwgs.User" user "User.Drawings")
		(19 "Cmts.User" user "User.Comments")
		(21 "Eco1.User" user "User.Eco1")
		(23 "Eco2.User" user "User.Eco2")
		(25 "Edge.Cuts" user "Board Geometry/Outline")
		(27 "Margin" user)
		(31 "F.CrtYd" user "Package Geometry/Place Bound Top")
		(29 "B.CrtYd" user "Package Geometry/Place Bound Bottom")
		(35 "F.Fab" user "Ref Des/Assembly Top")
		(33 "B.Fab" user "Ref Des/Assembly Bottom")
	)
	(footprint ""
		(layer "B.Cu")
		(at 106.891074 -412.028386 90)
		(property "Reference" "C6"
			(at 0 0 90)
			(layer "B.SilkS")
			(hide yes)
			(effects
				(font
					(size 1.27 1.27)
				)
				(justify mirror)
			)
		)
		(property "Value" ""
			(at 0 0 90)
			(layer "B.Fab")
			(effects
				(font
					(size 1.27 1.27)
				)
				(justify mirror)
			)
		)
		(duplicate_pad_numbers_are_jumpers no)
		(fp_line
			(start 0.7874 -0.4064)
			(end -0.7874 -0.4064)
			(stroke
				(width 0.1524)
				(type default)
			)
			(layer "B.SilkS")
		)
		(fp_line
			(start -0.7874 -0.4064)
			(end -0.7874 0.4064)
			(stroke
				(width 0.1524)
				(type default)
			)
			(layer "B.SilkS")
		)
		(fp_line
			(start 0.7874 0.4064)
			(end 0.7874 -0.4064)
			(stroke
				(width 0.1524)
				(type default)
			)
			(layer "B.SilkS")
		)
		(fp_line
			(start -0.7874 0.4064)
			(end 0.7874 0.4064)
			(stroke
				(width 0.1524)
				(type default)
			)
			(layer "B.SilkS")
		)
		(fp_line
			(start 0.67945 -0.305054)
			(end 0.12065 -0.305054)
			(stroke
				(width 0.1)
				(type default)
			)
			(layer "B.Fab")
		)
		(fp_line
			(start 0.12065 -0.305054)
			(end 0.12065 -0.2794)
			(stroke
				(width 0.1)
				(type default)
			)
			(layer "B.Fab")
		)
		(fp_line
			(start -0.12065 -0.3048)
			(end -0.67945 -0.3048)
			(stroke
				(width 0.1)
				(type default)
			)
			(layer "B.Fab")
		)
		(fp_line
			(start -0.67945 -0.3048)
			(end -0.67945 0.3048)
			(stroke
				(width 0.1)
				(type default)
			)
			(layer "B.Fab")
		)
		(fp_line
			(start 0.12065 -0.2794)
			(end -0.12065 -0.2794)
			(stroke
				(width 0.1)
				(type default)
			)
			(layer "B.Fab")
		)
		(fp_line
			(start -0.12065 -0.2794)
			(end -0.12065 -0.3048)
			(stroke
				(width 0.1)
				(type default)
			)
			(layer "B.Fab")
		)
		(fp_line
			(start 0.12065 0.2794)
			(end 0.12065 0.3048)
			(stroke
				(width 0.1)
				(type default)
			)
			(layer "B.Fab")
		)
		(fp_line
			(start -0.120396 0.2794)
			(end 0.12065 0.2794)
			(stroke
				(width 0.1)
				(type default)
			)
			(layer "B.Fab")
		)
		(fp_line
			(start 0.67945 0.3048)
			(end 0.67945 -0.305054)
			(stroke
				(width 0.1)
				(type default)
			)
			(layer "B.Fab")
		)
		(fp_line
			(start 0.12065 0.3048)
			(end 0.67945 0.3048)
			(stroke
				(width 0.1)
				(type default)
			)
			(layer "B.Fab")
		)
		(fp_line
			(start -0.120396 0.3048)
			(end -0.120396 0.2794)
			(stroke
				(width 0.1)
				(type default)
			)
			(layer "B.Fab")
		)
		(fp_line
			(start -0.67945 0.3048)
			(end -0.120396 0.3048)
			(stroke
				(width 0.1)
				(type default)
			)
			(layer "B.Fab")
		)
		(pad "1" smd circle
			(at 0.40005 0 270)
			(size 0 0)
			(layers "B.Cu" "B.Mask" "B.Paste")
			(net "HGX_DETECT_N_ISO")
		)
		(pad "2" smd circle
			(at -0.40005 0 270)
			(size 0 0)
			(layers "B.Cu" "B.Mask" "B.Paste")
			(net "GND")
		)
	)
	(footprint ""
		(layer "B.Cu")
		(at 138.65352 -39.749222 180)
		(property "Reference" "C6059"
			(at 0 0 0)
			(layer "B.SilkS")
			(hide yes)
			(effects
				(font
					(size 1.27 1.27)
				)
				(justify mirror)
			)
		)
		(property "Value" ""
			(at 0 0 0)
			(layer "B.Fab")
			(effects
				(font
					(size 1.27 1.27)
				)
				(justify mirror)
			)
		)
		(duplicate_pad_numbers_are_jumpers no)
		(fp_line
			(start 0.7874 0.4064)
			(end 0.7874 -0.4064)
			(stroke
				(width 0.1524)
				(type default)
			)
			(layer "B.SilkS")
		)
		(fp_line
			(start 0.7874 -0.4064)
			(end -0.7874 -0.4064)
			(stroke
				(width 0.1524)
				(type default)
			)
			(layer "B.SilkS")
		)
		(fp_line
			(start -0.7874 0.4064)
			(end 0.7874 0.4064)
			(stroke
				(width 0.1524)
				(type default)
			)
			(layer "B.SilkS")
		)
		(fp_line
			(start -0.7874 -0.4064)
			(end -0.7874 0.4064)
			(stroke
				(width 0.1524)
				(type default)
			)
			(layer "B.SilkS")
		)
		(fp_line
			(start 0.67945 0.3048)
			(end 0.67945 -0.305054)
			(stroke
				(width 0.1)
				(type default)
			)
			(layer "B.Fab")
		)
		(fp_line
			(start 0.67945 -0.305054)
			(end 0.12065 -0.305054)
			(stroke
				(width 0.1)
				(type default)
			)
			(layer "B.Fab")
		)
		(fp_line
			(start 0.12065 0.3048)
			(end 0.67945 0.3048)
			(stroke
				(width 0.1)
				(type default)
			)
			(layer "B.Fab")
		)
		(fp_line
			(start 0.12065 0.2794)
			(end 0.12065 0.3048)
			(stroke
				(width 0.1)
				(type default)
			)
			(layer "B.Fab")
		)
		(fp_line
			(start 0.12065 -0.2794)
			(end -0.12065 -0.2794)
			(stroke
				(width 0.1)
				(type default)
			)
			(layer "B.Fab")
		)
		(fp_line
			(start 0.12065 -0.305054)
			(end 0.12065 -0.2794)
			(stroke
				(width 0.1)
				(type default)
			)
			(layer "B.Fab")
		)
		(fp_line
			(start -0.120396 0.3048)
			(end -0.120396 0.2794)
			(stroke
				(width 0.1)
				(type default)
			)
			(layer "B.Fab")
		)
		(fp_line
			(start -0.120396 0.2794)
			(end 0.12065 0.2794)
			(stroke
				(width 0.1)
				(type default)
			)
			(layer "B.Fab")
		)
		(fp_line
			(start -0.12065 -0.2794)
			(end -0.12065 -0.3048)
			(stroke
				(width 0.1)
				(type default)
			)
			(layer "B.Fab")
		)
		(fp_line
			(start -0.12065 -0.3048)
			(end -0.67945 -0.3048)
			(stroke
				(width 0.1)
				(type default)
			)
			(layer "B.Fab")
		)
		(fp_line
			(start -0.67945 0.3048)
			(end -0.120396 0.3048)
			(stroke
				(width 0.1)
				(type default)
			)
			(layer "B.Fab")
		)
		(fp_line
			(start -0.67945 -0.3048)
			(end -0.67945 0.3048)
			(stroke
				(width 0.1)
				(type default)
			)
			(layer "B.Fab")
		)
		(pad "1" smd circle
			(at 0.40005 0)
			(size 0 0)
			(layers "B.Cu" "B.Mask" "B.Paste")
			(net "P1V2_AUX")
		)
		(pad "2" smd circle
			(at -0.40005 0)
			(size 0 0)
			(layers "B.Cu" "B.Mask" "B.Paste")
			(net "GND")
		)
	)
	(footprint ""
		(layer "B.Cu")
		(at 412.74619 -396.393162 -90)
		(property "Reference" "C776"
			(at 0 0 90)
			(layer "B.SilkS")
			(hide yes)
			(effects
				(font
					(size 1.27 1.27)
				)
				(justify mirror)
			)
		)
		(property "Value" ""
			(at 0 0 90)
			(layer "B.Fab")
			(effects
				(font
					(size 1.27 1.27)
				)
				(justify mirror)
			)
		)
		(duplicate_pad_numbers_are_jumpers no)
		(fp_line
			(start -0.299974 0.150114)
			(end 0.299974 0.150114)
			(stroke
				(width 0.1)
				(type default)
			)
			(layer "B.Fab")
		)
		(fp_line
			(start 0.299974 0.150114)
			(end 0.299974 -0.150114)
			(stroke
				(width 0.1)
				(type default)
			)
			(layer "B.Fab")
		)
		(fp_line
			(start -0.299974 -0.150114)
			(end -0.299974 0.150114)
			(stroke
				(width 0.1)
				(type default)
			)
			(layer "B.Fab")
		)
		(fp_line
			(start 0.299974 -0.150114)
			(end -0.299974 -0.150114)
			(stroke
				(width 0.1)
				(type default)
			)
			(layer "B.Fab")
		)
		(pad "1" smd rect
			(at 0.2667 0 90)
			(size 0.3048 0.381)
			(layers "B.Cu" "B.Mask" "B.Paste")
			(net "P1V8_CPU0_RT2_1A")
		)
		(pad "2" smd rect
			(at -0.2667 0 90)
			(size 0.3048 0.381)
			(layers "B.Cu" "B.Mask" "B.Paste")
			(net "GND")
		)
	)
)
